(kicad_pcb
	(version 20260206)
	(generator "pcbnew")
	(generator_version "10.0")
	(general
		(thickness 1.6)
		(legacy_teardrops no)
	)
	(paper "A4")
	(title_block
		(title "timecard-production-celestica-r4006 — R4006-B0001-02_R01.brd")
		(comment 1 "Time Appliance Project (Time Card) / footprints 305-310 of 1113")
	)
	(layers
		(0 "F.Cu" signal "TOP")
		(4 "In1.Cu" signal "L02_GND1")
		(6 "In2.Cu" signal "L03_SIG1")
		(8 "In3.Cu" signal "L04_GND2")
		(10 "In4.Cu" signal "L05_VCC1")
		(12 "In5.Cu" signal "L06_VCC2")
		(14 "In6.Cu" signal "L07_GND3")
		(16 "In7.Cu" signal "L08_SIG2")
		(18 "In8.Cu" signal "L09_GND4")
		(2 "B.Cu" signal "BOTTOM")
		(9 "F.Adhes" user "F.Adhesive")
		(11 "B.Adhes" user "B.Adhesive")
		(13 "F.Paste" user "Package Geometry/Pastemask Top")
		(15 "B.Paste" user "Package Geometry/Pastemask Bottom")
		(5 "F.SilkS" user "Ref Des/Silkscreen Top")
		(7 "B.SilkS" user "Ref Des/Silkscreen Bottom")
		(1 "F.Mask" user "Board Geometry/Soldermask Top")
		(3 "B.Mask" user "Board Geometry/Soldermask Bottom")
		(17 "Dwgs.User" user "User.Drawings")
		(19 "Cmts.User" user "User.Comments")
		(21 "Eco1.User" user "User.Eco1")
		(23 "Eco2.User" user "User.Eco2")
		(25 "Edge.Cuts" user "Board Geometry/Outline")
		(27 "Margin" user)
		(31 "F.CrtYd" user "Package Geometry/Place Bound Top")
		(29 "B.CrtYd" user "Package Geometry/Place Bound Bottom")
		(35 "F.Fab" user "Ref Des/Assembly Top")
		(33 "B.Fab" user "Ref Des/Assembly Bottom")
	)
	(footprint ""
		(layer "F.Cu")
		(at 89.281 -41.021 90)
		(property "Reference" "C155"
			(at -3.429 -0.21463 90)
			(unlocked yes)
			(layer "F.SilkS")
			(effects
				(font
					(size 0.7874 0.5842)
					(thickness 0.1524)
				)
			)
		)
		(property "Value" "VAL*"
			(at 0.0762 3.134106 90)
			(unlocked yes)
			(layer "F.Fab")
			(hide yes)
			(effects
				(font
					(size 0.7874 0.5842)
					(thickness 0.1524)
				)
			)
		)
		(property "Tolerance" "TOL*"
			(at 0.0762 4.048506 90)
			(unlocked yes)
			(layer "Cmts.User")
			(hide yes)
			(effects
				(font
					(size 0.7874 0.5842)
					(thickness 0.1524)
				)
			)
		)
		(property "User Part Number" "PARTNUM*"
			(at 0.1016 5.013706 90)
			(unlocked yes)
			(layer "Cmts.User")
			(hide yes)
			(effects
				(font
					(size 0.7874 0.5842)
					(thickness 0.1524)
				)
			)
		)
		(property "Device Type" "CAPACITOR-G107-0F476-AM,47UF,2A"
			(at 0.0508 2.194306 90)
			(unlocked yes)
			(layer "F.Fab")
			(hide yes)
			(effects
				(font
					(size 0.7874 0.5842)
					(thickness 0.1524)
				)
			)
		)
		(duplicate_pad_numbers_are_jumpers no)
		(fp_line
			(start 1.5748 -0.9398)
			(end -1.5748 -0.9398)
			(stroke
				(width 0.1)
				(type default)
			)
			(layer "F.SilkS")
		)
		(fp_line
			(start -1.5748 -0.9398)
			(end -1.5748 0.9398)
			(stroke
				(width 0.1)
				(type default)
			)
			(layer "F.SilkS")
		)
		(fp_line
			(start 1.5748 0.9398)
			(end 1.5748 -0.9398)
			(stroke
				(width 0.1)
				(type default)
			)
			(layer "F.SilkS")
		)
		(fp_line
			(start -1.5748 0.9398)
			(end 1.5748 0.9398)
			(stroke
				(width 0.1)
				(type default)
			)
			(layer "F.SilkS")
		)
		(fp_rect
			(start -1.5748 -0.9398)
			(end 1.5748 0.9398)
			(stroke
				(width 0)
				(type default)
			)
			(fill no)
			(layer "F.CrtYd")
		)
		(fp_line
			(start 1.016 -0.635)
			(end -1.016 -0.635)
			(stroke
				(width 0.1)
				(type default)
			)
			(layer "F.Fab")
		)
		(fp_line
			(start -1.016 -0.635)
			(end -1.016 0.635)
			(stroke
				(width 0.1)
				(type default)
			)
			(layer "F.Fab")
		)
		(fp_line
			(start 1.016 0.635)
			(end 1.016 -0.635)
			(stroke
				(width 0.1)
				(type default)
			)
			(layer "F.Fab")
		)
		(fp_line
			(start -1.016 0.635)
			(end 1.016 0.635)
			(stroke
				(width 0.1)
				(type default)
			)
			(layer "F.Fab")
		)
		(pad "1" smd rect
			(at -0.8382 0 90)
			(size 0.9652 1.3716)
			(layers "F.Cu" "F.Mask" "F.Paste")
			(net "XP1R0V_FPGA")
		)
		(pad "2" smd rect
			(at 0.8382 0 90)
			(size 0.9652 1.3716)
			(layers "F.Cu" "F.Mask" "F.Paste")
			(net "SG")
		)
		(zone
			(layer "F.Cu")
			(hatch none 0.5)
			(connect_pads
				(clearance 0)
			)
			(min_thickness 0.25)
			(keepout
				(tracks allowed)
				(vias not_allowed)
				(pads allowed)
				(copperpour not_allowed)
				(footprints allowed)
			)
			(placement
				(enabled no)
				(sheetname "")
			)
			(fill
				(thermal_gap 0.5)
				(thermal_bridge_width 0.5)
				(island_removal_mode 0)
			)
			(polygon
				(pts
					(xy 88.646 -40.7924) (xy 89.916 -40.7924) (xy 89.916 -41.2496) (xy 88.646 -41.2496)
				)
			)
		)
	)
	(footprint ""
		(layer "F.Cu")
		(at 83.947 -67.31)
		(property "Reference" "TP17"
			(at -1.8034 -0.85725 0)
			(unlocked yes)
			(layer "F.SilkS")
			(effects
				(font
					(size 0.635 0.4064)
					(thickness 0.1524)
				)
				(justify left)
			)
		)
		(property "Value" ""
			(at 0 0 0)
			(layer "F.Fab")
			(effects
				(font
					(size 1.27 1.27)
				)
			)
		)
		(property "Device Type" "TP_PIONT-TP010CT020B030_PTH-TPA"
			(at -1.341882 0.996696 0)
			(unlocked yes)
			(layer "F.Fab")
			(hide yes)
			(effects
				(font
					(size 0.7874 0.5842)
					(thickness 0.000001)
				)
				(justify left)
			)
		)
		(duplicate_pad_numbers_are_jumpers no)
		(fp_poly
			(pts
				(arc
					(start 0.889 0)
					(mid -0.889 0)
					(end 0.889 0)
				)
			)
			(stroke
				(width 0)
				(type default)
			)
			(fill no)
			(layer "B.CrtYd")
		)
		(fp_poly
			(pts
				(arc
					(start 0.889 0)
					(mid -0.889 0)
					(end 0.889 0)
				)
			)
			(stroke
				(width 0)
				(type default)
			)
			(fill no)
			(layer "F.CrtYd")
		)
		(pad "1" thru_hole circle
			(at 0 0)
			(size 0.508 0.508)
			(drill 0.254)
			(layers "*.Cu" "*.Mask")
			(remove_unused_layers no)
			(net "R_BNO080_INT_N")
			(clearance 0.1016)
			(padstack
				(mode front_inner_back)
				(layer "Inner"
					(shape circle)
					(size 0.508 0.508)
					(clearance 0.1016)
				)
				(layer "B.Cu"
					(shape circle)
					(size 0.762 0.762)
					(clearance -0.0254)
				)
			)
		)
	)
	(footprint ""
		(layer "F.Cu")
		(at 89.8652 -98.8568 180)
		(property "Reference" "C16"
			(at -1.905 -2.83337 0)
			(unlocked yes)
			(layer "F.SilkS")
			(effects
				(font
					(size 0.7874 0.5842)
					(thickness 0.1524)
				)
			)
		)
		(property "Value" "VAL*"
			(at 0.193548 2.13614 180)
			(unlocked yes)
			(layer "F.Fab")
			(hide yes)
			(effects
				(font
					(size 0.7874 0.5842)
					(thickness 0.1524)
				)
			)
		)
		(property "User Part Number" "PARTNUM*"
			(at 0.216154 4.185666 180)
			(unlocked yes)
			(layer "Cmts.User")
			(hide yes)
			(effects
				(font
					(size 0.7874 0.5842)
					(thickness 0.1524)
				)
			)
		)
		(property "Device Type" "CAPACITOR-G104-0B101-FK,100PF,A"
			(at 0.184404 1.180592 180)
			(unlocked yes)
			(layer "F.Fab")
			(hide yes)
			(effects
				(font
					(size 0.7874 0.5842)
					(thickness 0.1524)
				)
			)
		)
		(property "Tolerance" "TOL*"
			(at 0.216154 3.1496 180)
			(unlocked yes)
			(layer "Cmts.User")
			(hide yes)
			(effects
				(font
					(size 0.7874 0.5842)
					(thickness 0.1524)
				)
			)
		)
		(duplicate_pad_numbers_are_jumpers no)
		(fp_line
			(start 0.671322 0.4445)
			(end -0.671322 0.4445)
			(stroke
				(width 0.1)
				(type default)
			)
			(layer "F.SilkS")
		)
		(fp_line
			(start 0.671322 -0.4445)
			(end 0.671322 0.4445)
			(stroke
				(width 0.1)
				(type default)
			)
			(layer "F.SilkS")
		)
		(fp_line
			(start -0.671322 0.4445)
			(end -0.671322 -0.4445)
			(stroke
				(width 0.1)
				(type default)
			)
			(layer "F.SilkS")
		)
		(fp_line
			(start -0.671322 -0.4445)
			(end 0.671322 -0.4445)
			(stroke
				(width 0.1)
				(type default)
			)
			(layer "F.SilkS")
		)
		(fp_rect
			(start 0.671322 -0.4445)
			(end -0.671322 0.4445)
			(stroke
				(width 0)
				(type default)
			)
			(fill no)
			(layer "F.CrtYd")
		)
		(fp_line
			(start 0.31496 0.1651)
			(end 0.31496 -0.1651)
			(stroke
				(width 0.1)
				(type default)
			)
			(layer "F.Fab")
		)
		(fp_line
			(start 0.31496 -0.1651)
			(end -0.31496 -0.1651)
			(stroke
				(width 0.1)
				(type default)
			)
			(layer "F.Fab")
		)
		(fp_line
			(start -0.31496 0.1651)
			(end 0.31496 0.1651)
			(stroke
				(width 0.1)
				(type default)
			)
			(layer "F.Fab")
		)
		(fp_line
			(start -0.31496 -0.1651)
			(end -0.31496 0.1651)
			(stroke
				(width 0.1)
				(type default)
			)
			(layer "F.Fab")
		)
		(pad "1" smd rect
			(at -0.264922 0 180)
			(size 0.3048 0.381)
			(layers "F.Cu" "F.Mask" "F.Paste")
			(net "UNNAMED_517_CAPACITOR_I30_1")
		)
		(pad "2" smd rect
			(at 0.264922 0 180)
			(size 0.3048 0.381)
			(layers "F.Cu" "F.Mask" "F.Paste")
			(net "XP3R3V_FB_R_TO_AGND")
		)
		(zone
			(layer "F.Cu")
			(hatch none 0.5)
			(connect_pads
				(clearance 0)
			)
			(min_thickness 0.25)
			(keepout
				(tracks allowed)
				(vias not_allowed)
				(pads allowed)
				(copperpour not_allowed)
				(footprints allowed)
			)
			(placement
				(enabled no)
				(sheetname "")
			)
			(fill
				(thermal_gap 0.5)
				(thermal_bridge_width 0.5)
				(island_removal_mode 0)
			)
			(polygon
				(pts
					(xy 89.752678 -98.6663) (xy 89.977722 -98.6663) (xy 89.977722 -99.0473) (xy 89.752678 -99.0473)
				)
			)
		)
	)
	(footprint ""
		(layer "F.Cu")
		(at 16.3576 -17.78)
		(property "Reference" "TP31"
			(at 0.38735 3.6322 90)
			(unlocked yes)
			(layer "F.SilkS")
			(effects
				(font
					(size 0.635 0.4064)
					(thickness 0.1524)
				)
				(justify left)
			)
		)
		(property "Value" ""
			(at 0 0 0)
			(layer "F.Fab")
			(effects
				(font
					(size 1.27 1.27)
				)
			)
		)
		(property "Device Type" "TP_PIONT-TP010CT020B030_PTH-TPA"
			(at -1.341882 0.996696 0)
			(unlocked yes)
			(layer "F.Fab")
			(hide yes)
			(effects
				(font
					(size 0.7874 0.5842)
					(thickness 0.000001)
				)
				(justify left)
			)
		)
		(duplicate_pad_numbers_are_jumpers no)
		(fp_poly
			(pts
				(arc
					(start 0.889 0)
					(mid -0.889 0)
					(end 0.889 0)
				)
			)
			(stroke
				(width 0)
				(type default)
			)
			(fill no)
			(layer "B.CrtYd")
		)
		(fp_poly
			(pts
				(arc
					(start 0.889 0)
					(mid -0.889 0)
					(end 0.889 0)
				)
			)
			(stroke
				(width 0)
				(type default)
			)
			(fill no)
			(layer "F.CrtYd")
		)
		(pad "1" thru_hole circle
			(at 0 0)
			(size 0.508 0.508)
			(drill 0.254)
			(layers "*.Cu" "*.Mask")
			(remove_unused_layers no)
			(net "SMA4_SIG_IN_BF_EN_N")
			(clearance 0.1016)
			(padstack
				(mode front_inner_back)
				(layer "Inner"
					(shape circle)
					(size 0.508 0.508)
					(clearance 0.1016)
				)
				(layer "B.Cu"
					(shape circle)
					(size 0.762 0.762)
					(clearance -0.0254)
				)
			)
		)
	)
	(footprint ""
		(layer "F.Cu")
		(at 127.127 -21.082)
		(property "Reference" "U37"
			(at -0.889 -3.64363 0)
			(unlocked yes)
			(layer "F.SilkS")
			(effects
				(font
					(size 0.7874 0.5842)
					(thickness 0.1524)
				)
			)
		)
		(property "Value" ""
			(at 0 0 0)
			(layer "F.Fab")
			(effects
				(font
					(size 1.27 1.27)
				)
			)
		)
		(property "Device Type" "TS3A5018PWR_TSSOP16-G220-10324A"
			(at 0 0.924306 0)
			(unlocked yes)
			(layer "F.Fab")
			(hide yes)
			(effects
				(font
					(size 0.7874 0.5842)
					(thickness 0.000001)
				)
			)
		)
		(property "User Part Number" "PARTNUM*"
			(at 0.254 1.940306 0)
			(unlocked yes)
			(layer "Cmts.User")
			(hide yes)
			(effects
				(font
					(size 0.7874 0.5842)
					(thickness 0.000001)
				)
			)
		)
		(duplicate_pad_numbers_are_jumpers no)
		(fp_line
			(start -4.0767 -2.7559)
			(end 4.0767 -2.7559)
			(stroke
				(width 0.1)
				(type default)
			)
			(layer "F.SilkS")
		)
		(fp_line
			(start -4.0767 2.7559)
			(end -4.0767 -2.7559)
			(stroke
				(width 0.1)
				(type default)
			)
			(layer "F.SilkS")
		)
		(fp_line
			(start 4.0767 -2.7559)
			(end 4.0767 2.7559)
			(stroke
				(width 0.1)
				(type default)
			)
			(layer "F.SilkS")
		)
		(fp_line
			(start 4.0767 2.7559)
			(end -4.0767 2.7559)
			(stroke
				(width 0.1)
				(type default)
			)
			(layer "F.SilkS")
		)
		(fp_poly
			(pts
				(arc
					(start -3.937 -3.175)
					(mid -4.699 -3.175)
					(end -3.937 -3.175)
				)
			)
			(stroke
				(width 0)
				(type default)
			)
			(fill yes)
			(layer "F.SilkS")
		)
		(fp_rect
			(start -4.3307 3.0099)
			(end 4.3307 -3.0099)
			(stroke
				(width 0)
				(type default)
			)
			(fill no)
			(layer "F.CrtYd")
		)
		(fp_line
			(start -2.1971 -2.5019)
			(end 2.1971 -2.5019)
			(stroke
				(width 0.1)
				(type default)
			)
			(layer "F.Fab")
		)
		(fp_line
			(start -2.1971 2.5019)
			(end -2.1971 -2.5019)
			(stroke
				(width 0.1)
				(type default)
			)
			(layer "F.Fab")
		)
		(fp_line
			(start 2.1971 -2.5019)
			(end 2.1971 2.5019)
			(stroke
				(width 0.1)
				(type default)
			)
			(layer "F.Fab")
		)
		(fp_line
			(start 2.1971 2.5019)
			(end -2.1971 2.5019)
			(stroke
				(width 0.1)
				(type default)
			)
			(layer "F.Fab")
		)
		(fp_poly
			(pts
				(arc
					(start -1.114298 -1.942084)
					(mid -1.914398 -1.942084)
					(end -1.114298 -1.942084)
				)
			)
			(stroke
				(width 0)
				(type default)
			)
			(fill yes)
			(layer "F.Fab")
		)
		(fp_text user "8"
			(at -4.572 2.18567 0)
			(unlocked yes)
			(layer "F.SilkS")
			(effects
				(font
					(size 0.7874 0.5842)
					(thickness 0.1524)
				)
			)
		)
		(fp_text user "16"
			(at 4.064 -3.64363 0)
			(unlocked yes)
			(layer "F.SilkS")
			(effects
				(font
					(size 0.7874 0.5842)
					(thickness 0.1524)
				)
			)
		)
		(fp_text user "9"
			(at 4.699 2.96037 0)
			(unlocked yes)
			(layer "F.SilkS")
			(effects
				(font
					(size 0.7874 0.5842)
					(thickness 0.1524)
				)
			)
		)
		(fp_text user "8"
			(at -4.572 2.18567 0)
			(unlocked yes)
			(layer "F.Fab")
			(effects
				(font
					(size 0.7874 0.5842)
					(thickness 0.1524)
				)
			)
		)
		(fp_text user "9"
			(at 4.5466 2.31267 0)
			(unlocked yes)
			(layer "F.Fab")
			(effects
				(font
					(size 0.7874 0.5842)
					(thickness 0.1524)
				)
			)
		)
		(fp_text user "16"
			(at 4.8768 -2.38633 0)
			(unlocked yes)
			(layer "F.Fab")
			(effects
				(font
					(size 0.7874 0.5842)
					(thickness 0.1524)
				)
			)
		)
		(pad "1" smd rect
			(at -3.0353 -2.275078 90)
			(size 0.3556 1.5748)
			(layers "F.Cu" "F.Mask" "F.Paste")
			(net "MUX3_SEL")
		)
		(pad "2" smd rect
			(at -3.0353 -1.625092 90)
			(size 0.3556 1.5748)
			(layers "F.Cu" "F.Mask" "F.Paste")
			(net "FPGA_PCA9546_I2C_SDA")
		)
		(pad "3" smd rect
			(at -3.0353 -0.975106 90)
			(size 0.3556 1.5748)
			(layers "F.Cu" "F.Mask" "F.Paste")
			(net "FT4232_I2C_SDA")
		)
		(pad "4" smd rect
			(at -3.0353 -0.32512 90)
			(size 0.3556 1.5748)
			(layers "F.Cu" "F.Mask" "F.Paste")
			(net "PCA9546_I2C_SDA")
		)
		(pad "5" smd rect
			(at -3.0353 0.32512 90)
			(size 0.3556 1.5748)
			(layers "F.Cu" "F.Mask" "F.Paste")
			(net "FPGA_PCA9546_I2C_SCL")
		)
		(pad "6" smd rect
			(at -3.0353 0.975106 90)
			(size 0.3556 1.5748)
			(layers "F.Cu" "F.Mask" "F.Paste")
			(net "FT4232_I2C_SCL")
		)
		(pad "7" smd rect
			(at -3.0353 1.625092 90)
			(size 0.3556 1.5748)
			(layers "F.Cu" "F.Mask" "F.Paste")
			(net "PCA9546_I2C_SCL")
		)
		(pad "8" smd rect
			(at -3.0353 2.275078 90)
			(size 0.3556 1.5748)
			(layers "F.Cu" "F.Mask" "F.Paste")
			(net "SG")
		)
		(pad "9" smd rect
			(at 3.0353 2.275078 90)
			(size 0.3556 1.5748)
			(layers "F.Cu" "F.Mask" "F.Paste")
			(net "EEPROM_I2C_SDA")
		)
		(pad "10" smd rect
			(at 3.0353 1.625092 90)
			(size 0.3556 1.5748)
			(layers "F.Cu" "F.Mask" "F.Paste")
			(net "FT4232_I2C_SDA")
		)
		(pad "11" smd rect
			(at 3.0353 0.975106 90)
			(size 0.3556 1.5748)
			(layers "F.Cu" "F.Mask" "F.Paste")
			(net "FPGA_EEPROM_I2C_SDA")
		)
		(pad "12" smd rect
			(at 3.0353 0.32512 90)
			(size 0.3556 1.5748)
			(layers "F.Cu" "F.Mask" "F.Paste")
			(net "EEPROM_I2C_SCL")
		)
		(pad "13" smd rect
			(at 3.0353 -0.32512 90)
			(size 0.3556 1.5748)
			(layers "F.Cu" "F.Mask" "F.Paste")
			(net "FT4232_I2C_SCL")
		)
		(pad "14" smd rect
			(at 3.0353 -0.975106 90)
			(size 0.3556 1.5748)
			(layers "F.Cu" "F.Mask" "F.Paste")
			(net "FPGA_EEPROM_I2C_SCL")
		)
		(pad "15" smd rect
			(at 3.0353 -1.625092 90)
			(size 0.3556 1.5748)
			(layers "F.Cu" "F.Mask" "F.Paste")
			(net "UNNAMED_524_RESISTOR_I463_2")
		)
		(pad "16" smd rect
			(at 3.0353 -2.275078 90)
			(size 0.3556 1.5748)
			(layers "F.Cu" "F.Mask" "F.Paste")
			(net "XP3R3V_FPGA")
		)
	)
	(footprint ""
		(layer "F.Cu")
		(at 121.1072 -30.6578 90)
		(property "Reference" "TP193"
			(at -1.35255 0 0)
			(unlocked yes)
			(layer "F.SilkS")
			(effects
				(font
					(size 0.635 0.4064)
					(thickness 0.1524)
				)
				(justify left)
			)
		)
		(property "Value" ""
			(at 0 0 90)
			(layer "F.Fab")
			(effects
				(font
					(size 1.27 1.27)
				)
			)
		)
		(property "Device Type" "TP_PIONT-TP010CT020B030_PTH-TPA"
			(at -1.341882 0.996696 90)
			(unlocked yes)
			(layer "F.Fab")
			(hide yes)
			(effects
				(font
					(size 0.7874 0.5842)
					(thickness 0.1524)
				)
				(justify left)
			)
		)
		(duplicate_pad_numbers_are_jumpers no)
		(fp_poly
			(pts
				(arc
					(start 0 0.889)
					(mid 0 -0.889)
					(end 0 0.889)
				)
			)
			(stroke
				(width 0)
				(type default)
			)
			(fill no)
			(layer "B.CrtYd")
		)
		(fp_poly
			(pts
				(arc
					(start 0 0.889)
					(mid 0 -0.889)
					(end 0 0.889)
				)
			)
			(stroke
				(width 0)
				(type default)
			)
			(fill no)
			(layer "F.CrtYd")
		)
		(pad "1" thru_hole circle
			(at 0 0 90)
			(size 0.508 0.508)
			(drill 0.254)
			(layers "*.Cu" "*.Mask")
			(remove_unused_layers no)
			(net "IO_L21P_35")
			(clearance 0.1016)
			(padstack
				(mode front_inner_back)
				(layer "Inner"
					(shape circle)
					(size 0.508 0.508)
					(clearance 0.1016)
				)
				(layer "B.Cu"
					(shape circle)
					(size 0.762 0.762)
					(clearance -0.0254)
				)
			)
		)
	)
)
